# BASEBOARD_FAB2 (Tioga Pass) — schematic netlist excerpt (pin names and nets, part order shuffled) for the footprints in the layout excerpt that follows; sources: Cadence DE-HDL packaged netlist, KiCad conversion of Wiwynn_Tioga_Pass_MB.brd

R7F20  RES  100.0K 1% EMPTY  pkg 0402  page 215 : A = P3V3_STBY ; B = VR_PVDDQ_ABC_VREN
C3B4  CAP_A  0.1UF 16V 10% X7R  pkg 0402V  page 99 : A = PVCCIO_CPU1 ; B = GND
RT38  1R3F-GP  1%  pkg RCL_GP  page 210 : \1\ = VR_PVSA_CPU1_PHASE_SW_RC ; \2\ = GND

(kicad_pcb
	(version 20260206)
	(generator "pcbnew")
	(generator_version "10.0")
	(general
		(thickness 1.6)
		(legacy_teardrops no)
	)
	(paper "A4")
	(title_block
		(title "Wiwynn_Tioga_Pass_MB.brd")
		(comment 1 "Tioga Pass / footprints 593-595 of 4770")
	)
	(layers
		(0 "F.Cu" signal "TOP")
		(4 "In1.Cu" signal "L2GND")
		(6 "In2.Cu" signal "L3")
		(8 "In3.Cu" signal "L4GND")
		(10 "In4.Cu" signal "L5")
		(12 "In5.Cu" signal "L6GND")
		(14 "In6.Cu" signal "L7VCC")
		(16 "In7.Cu" signal "L8VCC")
		(18 "In8.Cu" signal "L9GND")
		(20 "In9.Cu" signal "L10")
		(22 "In10.Cu" signal "L11GND")
		(24 "In11.Cu" signal "L12")
		(26 "In12.Cu" signal "L13GND")
		(2 "B.Cu" signal "BOTTOM")
		(9 "F.Adhes" user "F.Adhesive")
		(11 "B.Adhes" user "B.Adhesive")
		(13 "F.Paste" user "Package Geometry/Pastemask Top")
		(15 "B.Paste" user "Package Geometry/Pastemask Bottom")
		(5 "F.SilkS" user "Ref Des/Silkscreen Top")
		(7 "B.SilkS" user "Ref Des/Silkscreen Bottom")
		(1 "F.Mask" user "Board Geometry/Soldermask Top")
		(3 "B.Mask" user "Board Geometry/Soldermask Bottom")
		(17 "Dwgs.User" user "User.Drawings")
		(19 "Cmts.User" user "User.Comments")
		(21 "Eco1.User" user "User.Eco1")
		(23 "Eco2.User" user "User.Eco2")
		(25 "Edge.Cuts" user "Board Geometry/Outline")
		(27 "Margin" user)
		(31 "F.CrtYd" user "Package Geometry/Place Bound Top")
		(29 "B.CrtYd" user "Package Geometry/Place Bound Bottom")
		(35 "F.Fab" user "Ref Des/Assembly Top")
		(33 "B.Fab" user "Ref Des/Assembly Bottom")
	)
	(footprint ""
		(layer "F.Cu")
		(at 157.97022 -125.1077 90)
		(property "Reference" "C3B4"
			(at 0 0 90)
			(layer "F.SilkS")
			(hide yes)
			(effects
				(font
					(size 1.27 1.27)
				)
			)
		)
		(property "Value" ""
			(at 0 0 90)
			(layer "F.Fab")
			(effects
				(font
					(size 1.27 1.27)
				)
			)
		)
		(duplicate_pad_numbers_are_jumpers no)
		(fp_poly
			(pts
				(xy 0.3048 -0.1016) (xy 0.3048 0.9906) (xy -0.3048 0.9906) (xy -0.3048 -0.1016)
			)
			(stroke
				(width 0)
				(type default)
			)
			(fill no)
			(layer "F.CrtYd")
		)
		(fp_line
			(start 0.3048 -0.1016)
			(end -0.3048 -0.1016)
			(stroke
				(width 0.1)
				(type default)
			)
			(layer "F.Fab")
		)
		(fp_line
			(start -0.3048 -0.1016)
			(end -0.3048 0.9906)
			(stroke
				(width 0.1)
				(type default)
			)
			(layer "F.Fab")
		)
		(fp_line
			(start 0.3048 0.9906)
			(end 0.3048 -0.1016)
			(stroke
				(width 0.1)
				(type default)
			)
			(layer "F.Fab")
		)
		(fp_line
			(start -0.3048 0.9906)
			(end 0.3048 0.9906)
			(stroke
				(width 0.1)
				(type default)
			)
			(layer "F.Fab")
		)
		(pad "1" smd rect
			(at 0 0 90)
			(size 0.508 0.508)
			(layers "F.Cu" "F.Mask" "F.Paste")
			(net "PVCCIO_CPU1")
		)
		(pad "2" smd rect
			(at 0 0.889 90)
			(size 0.508 0.508)
			(layers "F.Cu" "F.Mask" "F.Paste")
			(net "GND")
		)
		(zone
			(layer "F.Cu")
			(hatch none 0.5)
			(connect_pads
				(clearance 0)
			)
			(min_thickness 0.25)
			(keepout
				(tracks allowed)
				(vias not_allowed)
				(pads allowed)
				(copperpour not_allowed)
				(footprints allowed)
			)
			(placement
				(enabled no)
				(sheetname "")
			)
			(fill
				(thermal_gap 0.5)
				(thermal_bridge_width 0.5)
				(island_removal_mode 0)
			)
			(polygon
				(pts
					(xy 158.22422 -124.8537) (xy 158.22422 -125.3617) (xy 158.60522 -125.3617) (xy 158.60522 -124.8537)
				)
			)
		)
		(zone
			(layer "F.Cu")
			(hatch none 0.5)
			(connect_pads
				(clearance 0)
			)
			(min_thickness 0.25)
			(keepout
				(tracks not_allowed)
				(vias allowed)
				(pads allowed)
				(copperpour not_allowed)
				(footprints allowed)
			)
			(placement
				(enabled no)
				(sheetname "")
			)
			(fill
				(thermal_gap 0.5)
				(thermal_bridge_width 0.5)
				(island_removal_mode 0)
			)
			(polygon
				(pts
					(xy 158.60522 -124.8537) (xy 158.60522 -125.3617) (xy 158.22422 -125.3617) (xy 158.22422 -124.8537)
				)
			)
		)
	)
	(footprint ""
		(layer "F.Cu")
		(at 339.471 -21.209 90)
		(property "Reference" "R7F20"
			(at -0.8382 -0.67818 90)
			(unlocked yes)
			(layer "F.SilkS")
			(effects
				(font
					(size 0.4064 0.254)
					(thickness 0.1524)
				)
				(justify left)
			)
		)
		(property "Value" ""
			(at 0 0 90)
			(layer "F.Fab")
			(effects
				(font
					(size 1.27 1.27)
				)
			)
		)
		(duplicate_pad_numbers_are_jumpers no)
		(fp_poly
			(pts
				(xy -0.2794 -0.1016) (xy 0.2794 -0.1016) (xy 0.2794 0.9906) (xy -0.2794 0.9906)
			)
			(stroke
				(width 0)
				(type default)
			)
			(fill no)
			(layer "F.CrtYd")
		)
		(fp_line
			(start 0.2794 -0.1016)
			(end -0.2794 -0.1016)
			(stroke
				(width 0.1)
				(type default)
			)
			(layer "F.Fab")
		)
		(fp_line
			(start -0.2794 -0.1016)
			(end -0.2794 0.9906)
			(stroke
				(width 0.1)
				(type default)
			)
			(layer "F.Fab")
		)
		(fp_line
			(start 0.2794 0.9906)
			(end 0.2794 -0.1016)
			(stroke
				(width 0.1)
				(type default)
			)
			(layer "F.Fab")
		)
		(fp_line
			(start -0.2794 0.9906)
			(end 0.2794 0.9906)
			(stroke
				(width 0.1)
				(type default)
			)
			(layer "F.Fab")
		)
		(pad "1" smd rect
			(at 0 0 90)
			(size 0.508 0.508)
			(layers "F.Cu" "F.Mask" "F.Paste")
			(net "P3V3_STBY")
		)
		(pad "2" smd rect
			(at 0 0.889 90)
			(size 0.508 0.508)
			(layers "F.Cu" "F.Mask" "F.Paste")
			(net "VR_PVDDQ_ABC_VREN")
		)
		(zone
			(layer "F.Cu")
			(hatch none 0.5)
			(connect_pads
				(clearance 0)
			)
			(min_thickness 0.25)
			(keepout
				(tracks allowed)
				(vias not_allowed)
				(pads allowed)
				(copperpour not_allowed)
				(footprints allowed)
			)
			(placement
				(enabled no)
				(sheetname "")
			)
			(fill
				(thermal_gap 0.5)
				(thermal_bridge_width 0.5)
				(island_removal_mode 0)
			)
			(polygon
				(pts
					(xy 339.725 -20.955) (xy 339.725 -21.463) (xy 340.106 -21.463) (xy 340.106 -20.955)
				)
			)
		)
		(zone
			(layer "F.Cu")
			(hatch none 0.5)
			(connect_pads
				(clearance 0)
			)
			(min_thickness 0.25)
			(keepout
				(tracks not_allowed)
				(vias allowed)
				(pads allowed)
				(copperpour not_allowed)
				(footprints allowed)
			)
			(placement
				(enabled no)
				(sheetname "")
			)
			(fill
				(thermal_gap 0.5)
				(thermal_bridge_width 0.5)
				(island_removal_mode 0)
			)
			(polygon
				(pts
					(xy 340.106 -20.955) (xy 340.106 -21.463) (xy 339.725 -21.463) (xy 339.725 -20.955)
				)
			)
		)
	)
	(footprint ""
		(layer "F.Cu")
		(at 35.86734 -93.897196 -90)
		(property "Reference" "RT38"
			(at 0 0 270)
			(layer "F.SilkS")
			(hide yes)
			(effects
				(font
					(size 1.27 1.27)
				)
			)
		)
		(property "Value" "*"
			(at -0.0254 -2.6289 270)
			(unlocked yes)
			(layer "F.Fab")
			(hide yes)
			(effects
				(font
					(size 1.27 1.016)
					(thickness 0.1524)
				)
			)
		)
		(property "Device Type" "1R3F-GP_RCL_GP-1R3F-GP,64.1R00A"
			(at -0.0254 -4.1529 270)
			(unlocked yes)
			(layer "F.Fab")
			(hide yes)
			(effects
				(font
					(size 1.27 1.016)
					(thickness 0.1524)
				)
			)
		)
		(duplicate_pad_numbers_are_jumpers no)
		(fp_line
			(start -0.4826 0)
			(end -0.2032 0)
			(stroke
				(width 0.2032)
				(type default)
			)
			(layer "F.SilkS")
		)
		(fp_line
			(start 0.2032 0)
			(end 0.4826 0)
			(stroke
				(width 0.2032)
				(type default)
			)
			(layer "F.SilkS")
		)
		(fp_rect
			(start -0.5842 1.3335)
			(end 0.5842 -1.3335)
			(stroke
				(width 0)
				(type default)
			)
			(fill no)
			(layer "F.CrtYd")
		)
		(fp_rect
			(start -0.5842 1.3335)
			(end 0.5842 -1.3335)
			(stroke
				(width 0)
				(type default)
			)
			(fill no)
			(layer "F.Fab")
		)
		(pad "1" smd custom
			(at 0 -0.762 270)
			(size 0.2159 0.2159)
			(layers "F.Cu" "F.Mask" "F.Paste")
			(net "VR_PVSA_CPU1_PHASE_SW_RC")
			(options
				(clearance outline)
				(anchor circle)
			)
			(primitives
				(gr_poly
					(pts
						(arc
							(start -0.3302 -0.4318)
							(mid -0.402042 -0.402042)
							(end -0.4318 -0.3302)
						)
						(arc
							(start -0.4318 0.3302)
							(mid -0.402042 0.402042)
							(end -0.3302 0.4318)
						)
						(arc
							(start 0.3302 0.4318)
							(mid 0.402042 0.402042)
							(end 0.4318 0.3302)
						)
						(arc
							(start 0.4318 -0.3302)
							(mid 0.402042 -0.402042)
							(end 0.3302 -0.4318)
						)
					)
					(width 0)
					(fill yes)
				)
			)
		)
		(pad "2" smd custom
			(at 0 0.762 270)
			(size 0.2159 0.2159)
			(layers "F.Cu" "F.Mask" "F.Paste")
			(net "GND")
			(options
				(clearance outline)
				(anchor circle)
			)
			(primitives
				(gr_poly
					(pts
						(arc
							(start -0.3302 -0.4318)
							(mid -0.402042 -0.402042)
							(end -0.4318 -0.3302)
						)
						(arc
							(start -0.4318 0.3302)
							(mid -0.402042 0.402042)
							(end -0.3302 0.4318)
						)
						(arc
							(start 0.3302 0.4318)
							(mid 0.402042 0.402042)
							(end 0.4318 0.3302)
						)
						(arc
							(start 0.4318 -0.3302)
							(mid 0.402042 -0.402042)
							(end 0.3302 -0.4318)
						)
					)
					(width 0)
					(fill yes)
				)
			)
		)
	)
)
